# S9S_MB_2U (Grand Teton) — schematic netlist excerpt (pin names and nets, part order shuffled) for the footprints in the layout excerpt that follows; sources: Cadence DE-HDL packaged netlist, KiCad conversion of 03242023_DA0F0TMBIJ0_F0T_Motherboard_J_brd_V01_OCP.brd

R1382  Q_RES  1K 1% CHIP  pkg 0402LF  page 239 : A = P3V3_AUX ; B = JTAG_DBP_BMC_PRDY_N
C1038  Q_CAP  22UF 4V 20% X6S  pkg C0402  page 74 : A = PVCCIN_CPU0 ; B = GND

(kicad_pcb
	(version 20260206)
	(generator "pcbnew")
	(generator_version "10.0")
	(general
		(thickness 1.6)
		(legacy_teardrops no)
	)
	(paper "A4")
	(title_block
		(title "03242023_DA0F0TMBIJ0_F0T_Motherboard_J_brd_V01_OCP.brd")
		(comment 1 "Grand Teton / footprints 3995-3996 of 6105")
	)
	(layers
		(0 "F.Cu" signal "TOP")
		(4 "In1.Cu" signal "GND")
		(6 "In2.Cu" signal "IN1")
		(8 "In3.Cu" signal "GND1")
		(10 "In4.Cu" signal "IN2")
		(12 "In5.Cu" signal "GND2")
		(14 "In6.Cu" signal "IN3")
		(16 "In7.Cu" signal "GND3")
		(18 "In8.Cu" signal "VCC")
		(20 "In9.Cu" signal "VCC1")
		(22 "In10.Cu" signal "GND4")
		(24 "In11.Cu" signal "IN4")
		(26 "In12.Cu" signal "GND5")
		(28 "In13.Cu" signal "IN5")
		(30 "In14.Cu" signal "GND6")
		(32 "In15.Cu" signal "IN6")
		(34 "In16.Cu" signal "GND7")
		(2 "B.Cu" signal "BOTTOM")
		(9 "F.Adhes" user "F.Adhesive")
		(11 "B.Adhes" user "B.Adhesive")
		(13 "F.Paste" user "Package Geometry/Pastemask Top")
		(15 "B.Paste" user "Package Geometry/Pastemask Bottom")
		(5 "F.SilkS" user "Ref Des/Silkscreen Top")
		(7 "B.SilkS" user "Ref Des/Silkscreen Bottom")
		(1 "F.Mask" user "Board Geometry/Soldermask Top")
		(3 "B.Mask" user "Board Geometry/Soldermask Bottom")
		(17 "Dwgs.User" user "User.Drawings")
		(19 "Cmts.User" user "User.Comments")
		(21 "Eco1.User" user "User.Eco1")
		(23 "Eco2.User" user "User.Eco2")
		(25 "Edge.Cuts" user "Board Geometry/Outline")
		(27 "Margin" user)
		(31 "F.CrtYd" user "Package Geometry/Place Bound Top")
		(29 "B.CrtYd" user "Package Geometry/Place Bound Bottom")
		(35 "F.Fab" user "Ref Des/Assembly Top")
		(33 "B.Fab" user "Ref Des/Assembly Bottom")
	)
	(footprint ""
		(layer "F.Cu")
		(at 379.443996 -92.887292 -90)
		(property "Reference" "R1382"
			(at 0 0 270)
			(layer "F.SilkS")
			(hide yes)
			(effects
				(font
					(size 1.27 1.27)
				)
			)
		)
		(property "Value" ""
			(at 0 0 270)
			(layer "F.Fab")
			(effects
				(font
					(size 1.27 1.27)
				)
			)
		)
		(duplicate_pad_numbers_are_jumpers no)
		(fp_line
			(start -0.7874 0.4064)
			(end -0.7874 -0.4064)
			(stroke
				(width 0.1524)
				(type default)
			)
			(layer "F.SilkS")
		)
		(fp_line
			(start 0.7874 0.4064)
			(end -0.7874 0.4064)
			(stroke
				(width 0.1524)
				(type default)
			)
			(layer "F.SilkS")
		)
		(fp_line
			(start -0.7874 -0.4064)
			(end 0.7874 -0.4064)
			(stroke
				(width 0.1524)
				(type default)
			)
			(layer "F.SilkS")
		)
		(fp_line
			(start 0.7874 -0.4064)
			(end 0.7874 0.4064)
			(stroke
				(width 0.1524)
				(type default)
			)
			(layer "F.SilkS")
		)
		(fp_line
			(start -0.67945 0.3048)
			(end -0.67945 -0.305054)
			(stroke
				(width 0.1)
				(type default)
			)
			(layer "F.Fab")
		)
		(fp_line
			(start -0.12065 0.3048)
			(end -0.67945 0.3048)
			(stroke
				(width 0.1)
				(type default)
			)
			(layer "F.Fab")
		)
		(fp_line
			(start 0.120396 0.3048)
			(end 0.120396 0.2794)
			(stroke
				(width 0.1)
				(type default)
			)
			(layer "F.Fab")
		)
		(fp_line
			(start 0.67945 0.3048)
			(end 0.120396 0.3048)
			(stroke
				(width 0.1)
				(type default)
			)
			(layer "F.Fab")
		)
		(fp_line
			(start -0.12065 0.2794)
			(end -0.12065 0.3048)
			(stroke
				(width 0.1)
				(type default)
			)
			(layer "F.Fab")
		)
		(fp_line
			(start 0.120396 0.2794)
			(end -0.12065 0.2794)
			(stroke
				(width 0.1)
				(type default)
			)
			(layer "F.Fab")
		)
		(fp_line
			(start -0.12065 -0.2794)
			(end 0.12065 -0.2794)
			(stroke
				(width 0.1)
				(type default)
			)
			(layer "F.Fab")
		)
		(fp_line
			(start 0.12065 -0.2794)
			(end 0.12065 -0.3048)
			(stroke
				(width 0.1)
				(type default)
			)
			(layer "F.Fab")
		)
		(fp_line
			(start 0.12065 -0.3048)
			(end 0.67945 -0.3048)
			(stroke
				(width 0.1)
				(type default)
			)
			(layer "F.Fab")
		)
		(fp_line
			(start 0.67945 -0.3048)
			(end 0.67945 0.3048)
			(stroke
				(width 0.1)
				(type default)
			)
			(layer "F.Fab")
		)
		(fp_line
			(start -0.67945 -0.305054)
			(end -0.12065 -0.305054)
			(stroke
				(width 0.1)
				(type default)
			)
			(layer "F.Fab")
		)
		(fp_line
			(start -0.12065 -0.305054)
			(end -0.12065 -0.2794)
			(stroke
				(width 0.1)
				(type default)
			)
			(layer "F.Fab")
		)
		(pad "1" smd circle
			(at -0.40005 0 270)
			(size 0 0)
			(layers "F.Cu" "F.Mask" "F.Paste")
			(net "P3V3_AUX")
		)
		(pad "2" smd circle
			(at 0.40005 0 270)
			(size 0 0)
			(layers "F.Cu" "F.Mask" "F.Paste")
			(net "JTAG_DBP_BMC_PRDY_N")
		)
	)
	(footprint ""
		(layer "F.Cu")
		(at 354.282248 -249.320304 -90)
		(property "Reference" "C1038"
			(at 0 0 270)
			(layer "F.SilkS")
			(hide yes)
			(effects
				(font
					(size 1.27 1.27)
				)
			)
		)
		(property "Value" ""
			(at 0 0 270)
			(layer "F.Fab")
			(effects
				(font
					(size 1.27 1.27)
				)
			)
		)
		(duplicate_pad_numbers_are_jumpers no)
		(fp_line
			(start -0.7874 0.4064)
			(end -0.7874 -0.4064)
			(stroke
				(width 0.1524)
				(type default)
			)
			(layer "F.SilkS")
		)
		(fp_line
			(start 0.7874 0.4064)
			(end -0.7874 0.4064)
			(stroke
				(width 0.1524)
				(type default)
			)
			(layer "F.SilkS")
		)
		(fp_line
			(start -0.7874 -0.4064)
			(end 0.7874 -0.4064)
			(stroke
				(width 0.1524)
				(type default)
			)
			(layer "F.SilkS")
		)
		(fp_line
			(start 0.7874 -0.4064)
			(end 0.7874 0.4064)
			(stroke
				(width 0.1524)
				(type default)
			)
			(layer "F.SilkS")
		)
		(fp_line
			(start -0.67945 0.3048)
			(end -0.67945 -0.305054)
			(stroke
				(width 0.1)
				(type default)
			)
			(layer "F.Fab")
		)
		(fp_line
			(start -0.12065 0.3048)
			(end -0.67945 0.3048)
			(stroke
				(width 0.1)
				(type default)
			)
			(layer "F.Fab")
		)
		(fp_line
			(start 0.120396 0.3048)
			(end 0.120396 0.2794)
			(stroke
				(width 0.1)
				(type default)
			)
			(layer "F.Fab")
		)
		(fp_line
			(start 0.67945 0.3048)
			(end 0.120396 0.3048)
			(stroke
				(width 0.1)
				(type default)
			)
			(layer "F.Fab")
		)
		(fp_line
			(start -0.12065 0.2794)
			(end -0.12065 0.3048)
			(stroke
				(width 0.1)
				(type default)
			)
			(layer "F.Fab")
		)
		(fp_line
			(start 0.120396 0.2794)
			(end -0.12065 0.2794)
			(stroke
				(width 0.1)
				(type default)
			)
			(layer "F.Fab")
		)
		(fp_line
			(start -0.12065 -0.2794)
			(end 0.12065 -0.2794)
			(stroke
				(width 0.1)
				(type default)
			)
			(layer "F.Fab")
		)
		(fp_line
			(start 0.12065 -0.2794)
			(end 0.12065 -0.3048)
			(stroke
				(width 0.1)
				(type default)
			)
			(layer "F.Fab")
		)
		(fp_line
			(start 0.12065 -0.3048)
			(end 0.67945 -0.3048)
			(stroke
				(width 0.1)
				(type default)
			)
			(layer "F.Fab")
		)
		(fp_line
			(start 0.67945 -0.3048)
			(end 0.67945 0.3048)
			(stroke
				(width 0.1)
				(type default)
			)
			(layer "F.Fab")
		)
		(fp_line
			(start -0.67945 -0.305054)
			(end -0.12065 -0.305054)
			(stroke
				(width 0.1)
				(type default)
			)
			(layer "F.Fab")
		)
		(fp_line
			(start -0.12065 -0.305054)
			(end -0.12065 -0.2794)
			(stroke
				(width 0.1)
				(type default)
			)
			(layer "F.Fab")
		)
		(pad "1" smd circle
			(at -0.40005 0 270)
			(size 0 0)
			(layers "F.Cu" "F.Mask" "F.Paste")
			(net "PVCCIN_CPU0")
		)
		(pad "2" smd circle
			(at 0.40005 0 270)
			(size 0 0)
			(layers "F.Cu" "F.Mask" "F.Paste")
			(net "GND")
		)
	)
)
